(kicad_pcb
	(version 20260206)
	(generator "pcbnew")
	(generator_version "10.0")
	(general
		(thickness 1.6)
		(legacy_teardrops no)
	)
	(paper "A4")
	(title_block
		(title "03242023_DA0F0TMBIJ0_F0T_Motherboard_J_brd_V01_OCP.brd")
		(comment 1 "Grand Teton / footprint 3156 of 6105 (J106), pads 1-48 of 48")
	)
	(layers
		(0 "F.Cu" signal "TOP")
		(4 "In1.Cu" signal "GND")
		(6 "In2.Cu" signal "IN1")
		(8 "In3.Cu" signal "GND1")
		(10 "In4.Cu" signal "IN2")
		(12 "In5.Cu" signal "GND2")
		(14 "In6.Cu" signal "IN3")
		(16 "In7.Cu" signal "GND3")
		(18 "In8.Cu" signal "VCC")
		(20 "In9.Cu" signal "VCC1")
		(22 "In10.Cu" signal "GND4")
		(24 "In11.Cu" signal "IN4")
		(26 "In12.Cu" signal "GND5")
		(28 "In13.Cu" signal "IN5")
		(30 "In14.Cu" signal "GND6")
		(32 "In15.Cu" signal "IN6")
		(34 "In16.Cu" signal "GND7")
		(2 "B.Cu" signal "BOTTOM")
		(9 "F.Adhes" user "F.Adhesive")
		(11 "B.Adhes" user "B.Adhesive")
		(13 "F.Paste" user "Package Geometry/Pastemask Top")
		(15 "B.Paste" user "Package Geometry/Pastemask Bottom")
		(5 "F.SilkS" user "Ref Des/Silkscreen Top")
		(7 "B.SilkS" user "Ref Des/Silkscreen Bottom")
		(1 "F.Mask" user "Board Geometry/Soldermask Top")
		(3 "B.Mask" user "Board Geometry/Soldermask Bottom")
		(17 "Dwgs.User" user "User.Drawings")
		(19 "Cmts.User" user "User.Comments")
		(21 "Eco1.User" user "User.Eco1")
		(23 "Eco2.User" user "User.Eco2")
		(25 "Edge.Cuts" user "Board Geometry/Outline")
		(27 "Margin" user)
		(31 "F.CrtYd" user "Package Geometry/Place Bound Top")
		(29 "B.CrtYd" user "Package Geometry/Place Bound Bottom")
		(35 "F.Fab" user "Ref Des/Assembly Top")
		(33 "B.Fab" user "Ref Des/Assembly Bottom")
	)
	(footprint ""
		(layer "F.Cu")
		(at 381.750062 -440.489848)
		(property "Reference" "J106"
			(at -7.488682 21.48459 0)
			(unlocked yes)
			(layer "F.SilkS")
			(effects
				(font
					(size 0.7874 0.5842)
					(thickness 0.1524)
				)
				(justify left)
			)
		)
		(property "Value" ""
			(at 0 0 0)
			(layer "F.Fab")
			(effects
				(font
					(size 1.27 1.27)
				)
			)
		)
		(duplicate_pad_numbers_are_jumpers no)
		(pad "A1" thru_hole rect
			(at 0 0 180)
			(size 0.766318 0.766318)
			(drill 0.359918)
			(layers "*.Cu" "*.Mask")
			(remove_unused_layers no)
			(net "PRSNT_CABLE_SWB_B1_N")
			(clearance 0.0508)
			(thermal_gap 0.0508)
			(padstack
				(mode front_inner_back)
				(layer "Inner"
					(shape circle)
					(size 0.766318 0.766318)
					(clearance 0.0508)
				)
				(layer "B.Cu"
					(shape rect)
					(size 0.766318 0.766318)
					(clearance 0.0508)
				)
			)
		)
		(pad "A2" thru_hole circle
			(at 1.999996 0.199898 180)
			(size 0.906272 0.906272)
			(drill 0.499872)
			(layers "*.Cu" "*.Mask")
			(remove_unused_layers no)
			(net "GND")
			(clearance 0.0508)
			(thermal_gap 0.0508)
		)
		(pad "A3" thru_hole circle
			(at 3.999992 0 180)
			(size 0.766318 0.766318)
			(drill 0.359918)
			(layers "*.Cu" "*.Mask")
			(remove_unused_layers no)
			(net "FM_SWB_PWRGD")
			(clearance 0.0508)
			(thermal_gap 0.0508)
		)
		(pad "A4" thru_hole circle
			(at 5.999988 0.199898 180)
			(size 0.906272 0.906272)
			(drill 0.499872)
			(layers "*.Cu" "*.Mask")
			(remove_unused_layers no)
			(net "GND")
			(clearance 0.0508)
			(thermal_gap 0.0508)
		)
		(pad "A5" thru_hole circle
			(at 7.999984 0 180)
			(size 0.766318 0.766318)
			(drill 0.359918)
			(layers "*.Cu" "*.Mask")
			(remove_unused_layers no)
			(net "NC_J106_A5")
			(clearance 0.0508)
			(thermal_gap 0.0508)
		)
		(pad "A6" thru_hole circle
			(at 9.99998 0.199898 180)
			(size 0.906272 0.906272)
			(drill 0.499872)
			(layers "*.Cu" "*.Mask")
			(remove_unused_layers no)
			(net "GND")
			(clearance 0.0508)
			(thermal_gap 0.0508)
		)
		(pad "A7" thru_hole circle
			(at 11.999976 0 180)
			(size 0.766318 0.766318)
			(drill 0.359918)
			(layers "*.Cu" "*.Mask")
			(remove_unused_layers no)
			(net "PRSNT_CABLE_GPU_A1_N")
			(clearance 0.0508)
			(thermal_gap 0.0508)
		)
		(pad "A8" thru_hole circle
			(at 13.999972 0.199898 180)
			(size 0.906272 0.906272)
			(drill 0.499872)
			(layers "*.Cu" "*.Mask")
			(remove_unused_layers no)
			(net "GND")
			(clearance 0.0508)
			(thermal_gap 0.0508)
		)
		(pad "B1" thru_hole circle
			(at 0 1.199896 180)
			(size 0.906272 0.906272)
			(drill 0.499872)
			(layers "*.Cu" "*.Mask")
			(remove_unused_layers no)
			(net "GND")
			(clearance 0.0508)
			(thermal_gap 0.0508)
		)
		(pad "B3" thru_hole circle
			(at 3.999992 1.199896 180)
			(size 0.906272 0.906272)
			(drill 0.499872)
			(layers "*.Cu" "*.Mask")
			(remove_unused_layers no)
			(net "GND")
			(clearance 0.0508)
			(thermal_gap 0.0508)
		)
		(pad "B5" thru_hole circle
			(at 7.999984 1.199896 180)
			(size 0.906272 0.906272)
			(drill 0.499872)
			(layers "*.Cu" "*.Mask")
			(remove_unused_layers no)
			(net "GND")
			(clearance 0.0508)
			(thermal_gap 0.0508)
		)
		(pad "B7" thru_hole circle
			(at 11.999976 1.199896 180)
			(size 0.906272 0.906272)
			(drill 0.499872)
			(layers "*.Cu" "*.Mask")
			(remove_unused_layers no)
			(net "GND")
			(clearance 0.0508)
			(thermal_gap 0.0508)
		)
		(pad "D2" thru_hole circle
			(at 1.999996 3.800094 180)
			(size 0.906272 0.906272)
			(drill 0.499872)
			(layers "*.Cu" "*.Mask")
			(remove_unused_layers no)
			(net "GND")
			(clearance 0.0508)
			(thermal_gap 0.0508)
		)
		(pad "D4" thru_hole circle
			(at 5.999988 3.800094 180)
			(size 0.906272 0.906272)
			(drill 0.499872)
			(layers "*.Cu" "*.Mask")
			(remove_unused_layers no)
			(net "GND")
			(clearance 0.0508)
			(thermal_gap 0.0508)
		)
		(pad "D6" thru_hole circle
			(at 9.99998 3.800094 180)
			(size 0.906272 0.906272)
			(drill 0.499872)
			(layers "*.Cu" "*.Mask")
			(remove_unused_layers no)
			(net "GND")
			(clearance 0.0508)
			(thermal_gap 0.0508)
		)
		(pad "D8" thru_hole circle
			(at 13.999972 3.800094 180)
			(size 0.906272 0.906272)
			(drill 0.499872)
			(layers "*.Cu" "*.Mask")
			(remove_unused_layers no)
			(net "GND")
			(clearance 0.0508)
			(thermal_gap 0.0508)
		)
		(pad "E1" thru_hole circle
			(at 0 4.800092 180)
			(size 0.906272 0.906272)
			(drill 0.499872)
			(layers "*.Cu" "*.Mask")
			(remove_unused_layers no)
			(net "GND")
			(clearance 0.0508)
			(thermal_gap 0.0508)
		)
		(pad "E3" thru_hole circle
			(at 3.999992 4.800092 180)
			(size 0.906272 0.906272)
			(drill 0.499872)
			(layers "*.Cu" "*.Mask")
			(remove_unused_layers no)
			(net "GND")
			(clearance 0.0508)
			(thermal_gap 0.0508)
		)
		(pad "E5" thru_hole circle
			(at 7.999984 4.800092 180)
			(size 0.906272 0.906272)
			(drill 0.499872)
			(layers "*.Cu" "*.Mask")
			(remove_unused_layers no)
			(net "GND")
			(clearance 0.0508)
			(thermal_gap 0.0508)
		)
		(pad "E7" thru_hole circle
			(at 11.999976 4.800092 180)
			(size 0.906272 0.906272)
			(drill 0.499872)
			(layers "*.Cu" "*.Mask")
			(remove_unused_layers no)
			(net "GND")
			(clearance 0.0508)
			(thermal_gap 0.0508)
		)
		(pad "G2" thru_hole circle
			(at 1.999996 7.400036 180)
			(size 0.906272 0.906272)
			(drill 0.499872)
			(layers "*.Cu" "*.Mask")
			(remove_unused_layers no)
			(net "GND")
			(clearance 0.0508)
			(thermal_gap 0.0508)
		)
		(pad "G4" thru_hole circle
			(at 5.999988 7.400036 180)
			(size 0.906272 0.906272)
			(drill 0.499872)
			(layers "*.Cu" "*.Mask")
			(remove_unused_layers no)
			(net "GND")
			(clearance 0.0508)
			(thermal_gap 0.0508)
		)
		(pad "G6" thru_hole circle
			(at 9.99998 7.400036 180)
			(size 0.906272 0.906272)
			(drill 0.499872)
			(layers "*.Cu" "*.Mask")
			(remove_unused_layers no)
			(net "GND")
			(clearance 0.0508)
			(thermal_gap 0.0508)
		)
		(pad "G8" thru_hole circle
			(at 13.999972 7.400036 180)
			(size 0.906272 0.906272)
			(drill 0.499872)
			(layers "*.Cu" "*.Mask")
			(remove_unused_layers no)
			(net "GND")
			(clearance 0.0508)
			(thermal_gap 0.0508)
		)
		(pad "H1" thru_hole circle
			(at 0 8.400034 180)
			(size 0.906272 0.906272)
			(drill 0.499872)
			(layers "*.Cu" "*.Mask")
			(remove_unused_layers no)
			(net "GND")
			(clearance 0.0508)
			(thermal_gap 0.0508)
		)
		(pad "H3" thru_hole circle
			(at 3.999992 8.400034 180)
			(size 0.906272 0.906272)
			(drill 0.499872)
			(layers "*.Cu" "*.Mask")
			(remove_unused_layers no)
			(net "GND")
			(clearance 0.0508)
			(thermal_gap 0.0508)
		)
		(pad "H5" thru_hole circle
			(at 7.999984 8.400034 180)
			(size 0.906272 0.906272)
			(drill 0.499872)
			(layers "*.Cu" "*.Mask")
			(remove_unused_layers no)
			(net "GND")
			(clearance 0.0508)
			(thermal_gap 0.0508)
		)
		(pad "H7" thru_hole circle
			(at 11.999976 8.400034 180)
			(size 0.906272 0.906272)
			(drill 0.499872)
			(layers "*.Cu" "*.Mask")
			(remove_unused_layers no)
			(net "GND")
			(clearance 0.0508)
			(thermal_gap 0.0508)
		)
		(pad "J2" thru_hole circle
			(at 1.999996 10.999978 180)
			(size 0.906272 0.906272)
			(drill 0.499872)
			(layers "*.Cu" "*.Mask")
			(remove_unused_layers no)
			(net "GND")
			(clearance 0.0508)
			(thermal_gap 0.0508)
		)
		(pad "J4" thru_hole circle
			(at 5.999988 10.999978 180)
			(size 0.906272 0.906272)
			(drill 0.499872)
			(layers "*.Cu" "*.Mask")
			(remove_unused_layers no)
			(net "GND")
			(clearance 0.0508)
			(thermal_gap 0.0508)
		)
		(pad "J6" thru_hole circle
			(at 9.99998 10.999978 180)
			(size 0.906272 0.906272)
			(drill 0.499872)
			(layers "*.Cu" "*.Mask")
			(remove_unused_layers no)
			(net "GND")
			(clearance 0.0508)
			(thermal_gap 0.0508)
		)
		(pad "J8" thru_hole circle
			(at 13.999972 10.999978 180)
			(size 0.906272 0.906272)
			(drill 0.499872)
			(layers "*.Cu" "*.Mask")
			(remove_unused_layers no)
			(net "GND")
			(clearance 0.0508)
			(thermal_gap 0.0508)
		)
		(pad "K1" thru_hole circle
			(at 0 11.999976 180)
			(size 0.906272 0.906272)
			(drill 0.499872)
			(layers "*.Cu" "*.Mask")
			(remove_unused_layers no)
			(net "GND")
			(clearance 0.0508)
			(thermal_gap 0.0508)
		)
		(pad "K3" thru_hole circle
			(at 3.999992 11.999976 180)
			(size 0.906272 0.906272)
			(drill 0.499872)
			(layers "*.Cu" "*.Mask")
			(remove_unused_layers no)
			(net "GND")
			(clearance 0.0508)
			(thermal_gap 0.0508)
		)
		(pad "K5" thru_hole circle
			(at 7.999984 11.999976 180)
			(size 0.906272 0.906272)
			(drill 0.499872)
			(layers "*.Cu" "*.Mask")
			(remove_unused_layers no)
			(net "GND")
			(clearance 0.0508)
			(thermal_gap 0.0508)
		)
		(pad "K7" thru_hole circle
			(at 11.999976 11.999976 180)
			(size 0.906272 0.906272)
			(drill 0.499872)
			(layers "*.Cu" "*.Mask")
			(remove_unused_layers no)
			(net "GND")
			(clearance 0.0508)
			(thermal_gap 0.0508)
		)
		(pad "M2" thru_hole circle
			(at 1.999996 14.59992 180)
			(size 0.906272 0.906272)
			(drill 0.499872)
			(layers "*.Cu" "*.Mask")
			(remove_unused_layers no)
			(net "GND")
			(clearance 0.0508)
			(thermal_gap 0.0508)
		)
		(pad "M4" thru_hole circle
			(at 5.999988 14.59992 180)
			(size 0.906272 0.906272)
			(drill 0.499872)
			(layers "*.Cu" "*.Mask")
			(remove_unused_layers no)
			(net "GND")
			(clearance 0.0508)
			(thermal_gap 0.0508)
		)
		(pad "M6" thru_hole circle
			(at 9.99998 14.59992 180)
			(size 0.906272 0.906272)
			(drill 0.499872)
			(layers "*.Cu" "*.Mask")
			(remove_unused_layers no)
			(net "GND")
			(clearance 0.0508)
			(thermal_gap 0.0508)
		)
		(pad "M8" thru_hole circle
			(at 13.999972 14.59992 180)
			(size 0.906272 0.906272)
			(drill 0.499872)
			(layers "*.Cu" "*.Mask")
			(remove_unused_layers no)
			(net "GND")
			(clearance 0.0508)
			(thermal_gap 0.0508)
		)
		(pad "N1" thru_hole circle
			(at 0 15.599918 180)
			(size 0.906272 0.906272)
			(drill 0.499872)
			(layers "*.Cu" "*.Mask")
			(remove_unused_layers no)
			(net "GND")
			(clearance 0.0508)
			(thermal_gap 0.0508)
		)
		(pad "N2" thru_hole circle
			(at 1.999996 15.80007 180)
			(size 0.766318 0.766318)
			(drill 0.359918)
			(layers "*.Cu" "*.Mask")
			(remove_unused_layers no)
			(net "I3C_BMC_SWB_BUF_SDA")
			(clearance 0.0508)
			(thermal_gap 0.0508)
		)
		(pad "N3" thru_hole circle
			(at 3.999992 15.599918 180)
			(size 0.906272 0.906272)
			(drill 0.499872)
			(layers "*.Cu" "*.Mask")
			(remove_unused_layers no)
			(net "GND")
			(clearance 0.0508)
			(thermal_gap 0.0508)
		)
		(pad "N4" thru_hole circle
			(at 5.999988 15.80007 180)
			(size 0.766318 0.766318)
			(drill 0.359918)
			(layers "*.Cu" "*.Mask")
			(remove_unused_layers no)
			(net "I3C_BMC_SWB_BUF_SCL")
			(clearance 0.0508)
			(thermal_gap 0.0508)
		)
		(pad "N5" thru_hole circle
			(at 7.999984 15.599918 180)
			(size 0.906272 0.906272)
			(drill 0.499872)
			(layers "*.Cu" "*.Mask")
			(remove_unused_layers no)
			(net "GND")
			(clearance 0.0508)
			(thermal_gap 0.0508)
		)
		(pad "N6" thru_hole circle
			(at 9.99998 15.80007 180)
			(size 0.766318 0.766318)
			(drill 0.359918)
			(layers "*.Cu" "*.Mask")
			(remove_unused_layers no)
			(net "UART_BMC_BIC_RX")
			(clearance 0.0508)
			(thermal_gap 0.0508)
		)
		(pad "N7" thru_hole circle
			(at 11.999976 15.599918 180)
			(size 0.906272 0.906272)
			(drill 0.499872)
			(layers "*.Cu" "*.Mask")
			(remove_unused_layers no)
			(net "GND")
			(clearance 0.0508)
			(thermal_gap 0.0508)
		)
		(pad "N8" thru_hole circle
			(at 13.999972 15.80007 180)
			(size 0.766318 0.766318)
			(drill 0.359918)
			(layers "*.Cu" "*.Mask")
			(remove_unused_layers no)
			(net "UART_BMC_BIC_TX")
			(clearance 0.0508)
			(thermal_gap 0.0508)
		)
	)
)
